(kicad_pcb
	(version 20260206)
	(generator "pcbnew")
	(generator_version "10.0")
	(general
		(thickness 1.21888)
		(legacy_teardrops no)
	)
	(paper "A4")
	(title_block
		(title "timecard-proto-v0 — Timingcard_PCB.PcbDoc")
		(comment 1 "Time Appliance Project (Time Card) / footprint 31 of 167 (P1), pads 1-130 of 340")
	)
	(layers
		(0 "F.Cu" signal "TOP")
		(4 "In1.Cu" signal "SGND")
		(6 "In2.Cu" signal "IN1")
		(8 "In3.Cu" signal "IN2")
		(10 "In4.Cu" signal "SGND1")
		(2 "B.Cu" signal "BOTTOM")
		(9 "F.Adhes" user "F.Adhesive")
		(11 "B.Adhes" user "B.Adhesive")
		(13 "F.Paste" user "Top Paste")
		(15 "B.Paste" user "Bottom Paste")
		(5 "F.SilkS" user "Top Overlay")
		(7 "B.SilkS" user "Bottom Overlay")
		(1 "F.Mask" user "Top Solder")
		(3 "B.Mask" user "Bottom Solder")
		(17 "Dwgs.User" user "User.Drawings")
		(19 "Cmts.User" user "User.Comments")
		(21 "Eco1.User" user "User.Eco1")
		(23 "Eco2.User" user "User.Eco2")
		(25 "Edge.Cuts" user)
		(27 "Margin" user)
		(31 "F.CrtYd" user "Top Courtyard")
		(29 "B.CrtYd" user "Bottom Courtyard")
		(35 "F.Fab" user "Top Component Center")
		(33 "B.Fab" user "Bottom Component Center")
	)
	(footprint "FPGA_CONN:FPGA_CONN"
		(locked yes)
		(layer "F.Cu")
		(at 125.389655 117.45847)
		(property "Reference" "P1"
			(at -27.35726 -23.285325 0)
			(unlocked yes)
			(layer "F.SilkS")
			(effects
				(font
					(size 0.762 0.762)
					(thickness 0.2286)
				)
				(justify left bottom)
			)
		)
		(property "Value" "FPGA_CONN"
			(at -43.9575 52.70297 0)
			(unlocked yes)
			(layer "F.SilkS")
			(hide yes)
			(effects
				(font
					(size 1.524 1.524)
					(thickness 0.254)
				)
				(justify left bottom)
			)
		)
		(sheetname "FPGA")
		(sheetfile "FPGA.kicad_sch")
		(duplicate_pad_numbers_are_jumpers no)
		(pad "A-1" smd rect
			(at 21.78647 -9.87526)
			(size 1.54991 0.24994)
			(layers "F.Cu" "F.Mask" "F.Paste")
			(net "+5.0V")
		)
		(pad "A-2" smd rect
			(at 25.83624 -9.87526)
			(size 1.54991 0.24994)
			(layers "F.Cu" "F.Mask" "F.Paste")
			(net "+5.0V")
		)
		(pad "A-3" smd rect
			(at 21.78647 -9.37514)
			(size 1.54991 0.24994)
			(layers "F.Cu" "F.Mask" "F.Paste")
			(net "+5.0V")
		)
		(pad "A-4" smd rect
			(at 25.83624 -9.37514)
			(size 1.54991 0.24994)
			(layers "F.Cu" "F.Mask" "F.Paste")
			(net "+5.0V")
		)
		(pad "A-5" smd rect
			(at 21.78647 -8.87527)
			(size 1.54991 0.24994)
			(layers "F.Cu" "F.Mask" "F.Paste")
			(net "+5.0V")
		)
		(pad "A-6" smd rect
			(at 25.83624 -8.87527)
			(size 1.54991 0.24994)
			(layers "F.Cu" "F.Mask" "F.Paste")
			(net "+5.0V")
		)
		(pad "A-7" smd rect
			(at 21.78647 -8.37514)
			(size 1.54991 0.24994)
			(layers "F.Cu" "F.Mask" "F.Paste")
			(net "+5.0V")
		)
		(pad "A-8" smd rect
			(at 25.83624 -8.37514)
			(size 1.54991 0.24994)
			(layers "F.Cu" "F.Mask" "F.Paste")
			(net "+5.0V")
		)
		(pad "A-9" smd rect
			(at 21.78647 -7.87527)
			(size 1.54991 0.24994)
			(layers "F.Cu" "F.Mask" "F.Paste")
			(net "GND")
		)
		(pad "A-10" smd rect
			(at 25.83624 -7.87527)
			(size 1.54991 0.24994)
			(layers "F.Cu" "F.Mask" "F.Paste")
			(net "GND")
		)
		(pad "A-11" smd rect
			(at 21.78647 -7.37514)
			(size 1.54991 0.24994)
			(layers "F.Cu" "F.Mask" "F.Paste")
		)
		(pad "A-12" smd rect
			(at 25.83624 -7.37514)
			(size 1.54991 0.24994)
			(layers "F.Cu" "F.Mask" "F.Paste")
		)
		(pad "A-13" smd rect
			(at 21.78647 -6.87527)
			(size 1.54991 0.24994)
			(layers "F.Cu" "F.Mask" "F.Paste")
		)
		(pad "A-14" smd rect
			(at 25.83624 -6.87527)
			(size 1.54991 0.24994)
			(layers "F.Cu" "F.Mask" "F.Paste")
		)
		(pad "A-15" smd rect
			(at 21.78647 -6.37514)
			(size 1.54991 0.24994)
			(layers "F.Cu" "F.Mask" "F.Paste")
		)
		(pad "A-16" smd rect
			(at 25.83624 -6.37514)
			(size 1.54991 0.24994)
			(layers "F.Cu" "F.Mask" "F.Paste")
		)
		(pad "A-17" smd rect
			(at 21.78647 -5.87527)
			(size 1.54991 0.24994)
			(layers "F.Cu" "F.Mask" "F.Paste")
		)
		(pad "A-18" smd rect
			(at 25.83624 -5.87527)
			(size 1.54991 0.24994)
			(layers "F.Cu" "F.Mask" "F.Paste")
		)
		(pad "A-19" smd rect
			(at 21.78647 -5.37515)
			(size 1.54991 0.24994)
			(layers "F.Cu" "F.Mask" "F.Paste")
			(net "GND")
		)
		(pad "A-20" smd rect
			(at 25.83624 -5.37515)
			(size 1.54991 0.24994)
			(layers "F.Cu" "F.Mask" "F.Paste")
			(net "GND")
		)
		(pad "A-21" smd rect
			(at 21.78647 -4.87527)
			(size 1.54991 0.24994)
			(layers "F.Cu" "F.Mask" "F.Paste")
			(net "MOSI")
		)
		(pad "A-22" smd rect
			(at 25.83624 -4.87527)
			(size 1.54991 0.24994)
			(layers "F.Cu" "F.Mask" "F.Paste")
			(net "GPS1_RST")
		)
		(pad "A-23" smd rect
			(at 21.78647 -4.37515)
			(size 1.54991 0.24994)
			(layers "F.Cu" "F.Mask" "F.Paste")
			(net "MISO")
		)
		(pad "A-24" smd rect
			(at 25.83624 -4.37515)
			(size 1.54991 0.24994)
			(layers "F.Cu" "F.Mask" "F.Paste")
		)
		(pad "A-25" smd rect
			(at 21.78647 -3.87528)
			(size 1.54991 0.24994)
			(layers "F.Cu" "F.Mask" "F.Paste")
			(net "SCK")
		)
		(pad "A-26" smd rect
			(at 25.83624 -3.87528)
			(size 1.54991 0.24994)
			(layers "F.Cu" "F.Mask" "F.Paste")
		)
		(pad "A-27" smd rect
			(at 21.78647 -3.37515)
			(size 1.54991 0.24994)
			(layers "F.Cu" "F.Mask" "F.Paste")
			(net "CSN")
		)
		(pad "A-28" smd rect
			(at 25.83624 -3.37515)
			(size 1.54991 0.24994)
			(layers "F.Cu" "F.Mask" "F.Paste")
		)
		(pad "A-29" smd rect
			(at 21.78647 -2.87528)
			(size 1.54991 0.24994)
			(layers "F.Cu" "F.Mask" "F.Paste")
			(net "GND")
		)
		(pad "A-30" smd rect
			(at 25.83624 -2.87528)
			(size 1.54991 0.24994)
			(layers "F.Cu" "F.Mask" "F.Paste")
			(net "GND")
		)
		(pad "A-31" smd rect
			(at 21.78647 -2.37515)
			(size 1.54991 0.24994)
			(layers "F.Cu" "F.Mask" "F.Paste")
		)
		(pad "A-32" smd rect
			(at 25.83624 -2.37515)
			(size 1.54991 0.24994)
			(layers "F.Cu" "F.Mask" "F.Paste")
			(net "GPS1_TP1")
		)
		(pad "A-33" smd rect
			(at 21.78647 -1.87528)
			(size 1.54991 0.24994)
			(layers "F.Cu" "F.Mask" "F.Paste")
		)
		(pad "A-34" smd rect
			(at 25.83624 -1.87528)
			(size 1.54991 0.24994)
			(layers "F.Cu" "F.Mask" "F.Paste")
			(net "GPS1_TP2")
		)
		(pad "A-35" smd rect
			(at 21.78647 -1.37515)
			(size 1.54991 0.24994)
			(layers "F.Cu" "F.Mask" "F.Paste")
			(net "GPS2_RST")
		)
		(pad "A-36" smd rect
			(at 25.83624 -1.37515)
			(size 1.54991 0.24994)
			(layers "F.Cu" "F.Mask" "F.Paste")
		)
		(pad "A-37" smd rect
			(at 21.78647 -0.87528)
			(size 1.54991 0.24994)
			(layers "F.Cu" "F.Mask" "F.Paste")
		)
		(pad "A-38" smd rect
			(at 25.83624 -0.87528)
			(size 1.54991 0.24994)
			(layers "F.Cu" "F.Mask" "F.Paste")
		)
		(pad "A-39" smd rect
			(at 21.78647 -0.37516)
			(size 1.54991 0.24994)
			(layers "F.Cu" "F.Mask" "F.Paste")
			(net "GND")
		)
		(pad "A-40" smd rect
			(at 25.83624 -0.37516)
			(size 1.54991 0.24994)
			(layers "F.Cu" "F.Mask" "F.Paste")
			(net "GND")
		)
		(pad "A-41" smd rect
			(at 21.78647 0.12472)
			(size 1.54991 0.24994)
			(layers "F.Cu" "F.Mask" "F.Paste")
		)
		(pad "A-42" smd rect
			(at 25.83624 0.12472)
			(size 1.54991 0.24994)
			(layers "F.Cu" "F.Mask" "F.Paste")
		)
		(pad "A-43" smd rect
			(at 21.78647 0.62484)
			(size 1.54991 0.24994)
			(layers "F.Cu" "F.Mask" "F.Paste")
			(net "GPS2_TP1")
		)
		(pad "A-44" smd rect
			(at 25.83624 0.62484)
			(size 1.54991 0.24994)
			(layers "F.Cu" "F.Mask" "F.Paste")
			(net "EXT_EEPROM_WP")
		)
		(pad "A-45" smd rect
			(at 21.78647 1.12471)
			(size 1.54991 0.24994)
			(layers "F.Cu" "F.Mask" "F.Paste")
			(net "GPS2_TP2")
		)
		(pad "A-46" smd rect
			(at 25.83624 1.12471)
			(size 1.54991 0.24994)
			(layers "F.Cu" "F.Mask" "F.Paste")
			(net "IMU_INT")
		)
		(pad "A-47" smd rect
			(at 21.78647 1.62484)
			(size 1.54991 0.24994)
			(layers "F.Cu" "F.Mask" "F.Paste")
		)
		(pad "A-48" smd rect
			(at 25.83624 1.62484)
			(size 1.54991 0.24994)
			(layers "F.Cu" "F.Mask" "F.Paste")
			(net "IMU_NRST")
		)
		(pad "A-49" smd rect
			(at 21.78647 2.12471)
			(size 1.54991 0.24994)
			(layers "F.Cu" "F.Mask" "F.Paste")
			(net "GND")
		)
		(pad "A-50" smd rect
			(at 25.83624 2.12471)
			(size 1.54991 0.24994)
			(layers "F.Cu" "F.Mask" "F.Paste")
			(net "GND")
		)
		(pad "A-51" smd rect
			(at 21.78647 2.62484)
			(size 1.54991 0.24994)
			(layers "F.Cu" "F.Mask" "F.Paste")
		)
		(pad "A-52" smd rect
			(at 25.83624 2.62484)
			(size 1.54991 0.24994)
			(layers "F.Cu" "F.Mask" "F.Paste")
		)
		(pad "A-53" smd rect
			(at 21.78647 3.12471)
			(size 1.54991 0.24994)
			(layers "F.Cu" "F.Mask" "F.Paste")
		)
		(pad "A-54" smd rect
			(at 25.83624 3.12471)
			(size 1.54991 0.24994)
			(layers "F.Cu" "F.Mask" "F.Paste")
			(net "IMU_PS0")
		)
		(pad "A-55" smd rect
			(at 21.78647 3.62484)
			(size 1.54991 0.24994)
			(layers "F.Cu" "F.Mask" "F.Paste")
		)
		(pad "A-56" smd rect
			(at 25.83624 3.62484)
			(size 1.54991 0.24994)
			(layers "F.Cu" "F.Mask" "F.Paste")
			(net "IMU_PS1")
		)
		(pad "A-57" smd rect
			(at 21.78647 4.12471)
			(size 1.54991 0.24994)
			(layers "F.Cu" "F.Mask" "F.Paste")
		)
		(pad "A-58" smd rect
			(at 25.83624 4.12471)
			(size 1.54991 0.24994)
			(layers "F.Cu" "F.Mask" "F.Paste")
		)
		(pad "A-59" smd rect
			(at 21.78647 4.62483)
			(size 1.54991 0.24994)
			(layers "F.Cu" "F.Mask" "F.Paste")
			(net "GND")
		)
		(pad "A-60" smd rect
			(at 25.83624 4.62483)
			(size 1.54991 0.24994)
			(layers "F.Cu" "F.Mask" "F.Paste")
			(net "GND")
		)
		(pad "A-61" smd rect
			(at 21.78647 5.12471)
			(size 1.54991 0.24994)
			(layers "F.Cu" "F.Mask" "F.Paste")
		)
		(pad "A-62" smd rect
			(at 25.83624 5.12471)
			(size 1.54991 0.24994)
			(layers "F.Cu" "F.Mask" "F.Paste")
			(net "IMU_BOOT")
		)
		(pad "A-63" smd rect
			(at 21.78647 5.62483)
			(size 1.54991 0.24994)
			(layers "F.Cu" "F.Mask" "F.Paste")
		)
		(pad "A-64" smd rect
			(at 25.83624 5.62483)
			(size 1.54991 0.24994)
			(layers "F.Cu" "F.Mask" "F.Paste")
			(net "IMU_CLKSEL0")
		)
		(pad "A-65" smd rect
			(at 21.78647 6.1247)
			(size 1.54991 0.24994)
			(layers "F.Cu" "F.Mask" "F.Paste")
		)
		(pad "A-66" smd rect
			(at 25.83624 6.1247)
			(size 1.54991 0.24994)
			(layers "F.Cu" "F.Mask" "F.Paste")
		)
		(pad "A-67" smd rect
			(at 21.78647 6.62483)
			(size 1.54991 0.24994)
			(layers "F.Cu" "F.Mask" "F.Paste")
			(net "KEY2")
		)
		(pad "A-68" smd rect
			(at 25.83624 6.62483)
			(size 1.54991 0.24994)
			(layers "F.Cu" "F.Mask" "F.Paste")
		)
		(pad "A-69" smd rect
			(at 21.78647 7.1247)
			(size 1.54991 0.24994)
			(layers "F.Cu" "F.Mask" "F.Paste")
			(net "GND")
		)
		(pad "A-70" smd rect
			(at 25.83624 7.1247)
			(size 1.54991 0.24994)
			(layers "F.Cu" "F.Mask" "F.Paste")
			(net "GND")
		)
		(pad "A-71" smd rect
			(at 21.78647 7.62483)
			(size 1.54991 0.24994)
			(layers "F.Cu" "F.Mask" "F.Paste")
			(net "LED4")
		)
		(pad "A-72" smd rect
			(at 25.83624 7.62483)
			(size 1.54991 0.24994)
			(layers "F.Cu" "F.Mask" "F.Paste")
		)
		(pad "A-73" smd rect
			(at 21.78647 8.1247)
			(size 1.54991 0.24994)
			(layers "F.Cu" "F.Mask" "F.Paste")
			(net "LED3")
		)
		(pad "A-74" smd rect
			(at 25.83624 8.1247)
			(size 1.54991 0.24994)
			(layers "F.Cu" "F.Mask" "F.Paste")
		)
		(pad "A-75" smd rect
			(at 21.78647 8.62483)
			(size 1.54991 0.24994)
			(layers "F.Cu" "F.Mask" "F.Paste")
			(net "LED2")
		)
		(pad "A-76" smd rect
			(at 25.83624 8.62483)
			(size 1.54991 0.24994)
			(layers "F.Cu" "F.Mask" "F.Paste")
		)
		(pad "A-77" smd rect
			(at 21.78647 9.1247)
			(size 1.54991 0.24994)
			(layers "F.Cu" "F.Mask" "F.Paste")
			(net "LED1")
		)
		(pad "A-78" smd rect
			(at 25.83624 9.1247)
			(size 1.54991 0.24994)
			(layers "F.Cu" "F.Mask" "F.Paste")
		)
		(pad "A-79" smd rect
			(at 21.78647 9.62482)
			(size 1.54991 0.24994)
			(layers "F.Cu" "F.Mask" "F.Paste")
		)
		(pad "A-80" smd rect
			(at 25.83624 9.62482)
			(size 1.54991 0.24994)
			(layers "F.Cu" "F.Mask" "F.Paste")
		)
		(pad "A-81" smd rect
			(at 23.8 -11.3)
			(size 1.70002 1.35001)
			(layers "F.Cu" "F.Mask" "F.Paste")
		)
		(pad "A-82" thru_hole circle
			(at 23.81136 -10.1252)
			(size 0.55016 0.55016)
			(drill 0.55016)
			(layers "*.Cu" "*.Mask")
			(remove_unused_layers no)
			(thermal_bridge_angle 90)
		)
		(pad "A-83" thru_hole circle
			(at 23.81136 9.87476)
			(size 0.55016 0.55016)
			(drill 0.55016)
			(layers "*.Cu" "*.Mask")
			(remove_unused_layers no)
			(thermal_bridge_angle 90)
		)
		(pad "A-84" smd rect
			(at 23.8 11.05)
			(size 1.70002 1.35001)
			(layers "F.Cu" "F.Mask" "F.Paste")
		)
		(pad "B-1" smd rect
			(at -10.7014 -16.77035)
			(size 0.24994 1.54991)
			(layers "F.Cu" "F.Mask" "F.Paste")
		)
		(pad "B-2" smd rect
			(at -10.7014 -20.82012)
			(size 0.24994 1.54991)
			(layers "F.Cu" "F.Mask" "F.Paste")
		)
		(pad "B-3" smd rect
			(at -10.20128 -16.77035)
			(size 0.24994 1.54991)
			(layers "F.Cu" "F.Mask" "F.Paste")
		)
		(pad "B-4" smd rect
			(at -10.20128 -20.82012)
			(size 0.24994 1.54991)
			(layers "F.Cu" "F.Mask" "F.Paste")
		)
		(pad "B-5" smd rect
			(at -9.7014 -16.77035)
			(size 0.24994 1.54991)
			(layers "F.Cu" "F.Mask" "F.Paste")
		)
		(pad "B-6" smd rect
			(at -9.7014 -20.82012)
			(size 0.24994 1.54991)
			(layers "F.Cu" "F.Mask" "F.Paste")
			(net "OE_5356")
		)
		(pad "B-7" smd rect
			(at -9.20128 -16.77035)
			(size 0.24994 1.54991)
			(layers "F.Cu" "F.Mask" "F.Paste")
		)
		(pad "B-8" smd rect
			(at -9.20128 -20.82012)
			(size 0.24994 1.54991)
			(layers "F.Cu" "F.Mask" "F.Paste")
			(net "MAC_USB_PWR")
		)
		(pad "B-9" smd rect
			(at -8.70141 -16.77035)
			(size 0.24994 1.54991)
			(layers "F.Cu" "F.Mask" "F.Paste")
			(net "GND")
		)
		(pad "B-10" smd rect
			(at -8.70141 -20.82012)
			(size 0.24994 1.54991)
			(layers "F.Cu" "F.Mask" "F.Paste")
			(net "GND")
		)
		(pad "B-11" smd rect
			(at -8.20128 -16.77035)
			(size 0.24994 1.54991)
			(layers "F.Cu" "F.Mask" "F.Paste")
			(net "MAC_10Mout")
		)
		(pad "B-12" smd rect
			(at -8.20128 -20.82012)
			(size 0.24994 1.54991)
			(layers "F.Cu" "F.Mask" "F.Paste")
		)
		(pad "B-13" smd rect
			(at -7.70141 -16.77035)
			(size 0.24994 1.54991)
			(layers "F.Cu" "F.Mask" "F.Paste")
			(net "MAC_10Mout")
		)
		(pad "B-14" smd rect
			(at -7.70141 -20.82012)
			(size 0.24994 1.54991)
			(layers "F.Cu" "F.Mask" "F.Paste")
		)
		(pad "B-15" smd rect
			(at -7.20128 -16.77035)
			(size 0.24994 1.54991)
			(layers "F.Cu" "F.Mask" "F.Paste")
		)
		(pad "B-16" smd rect
			(at -7.20128 -20.82012)
			(size 0.24994 1.54991)
			(layers "F.Cu" "F.Mask" "F.Paste")
			(net "DCXO2")
		)
		(pad "B-17" smd rect
			(at -6.70141 -16.77035)
			(size 0.24994 1.54991)
			(layers "F.Cu" "F.Mask" "F.Paste")
		)
		(pad "B-18" smd rect
			(at -6.70141 -20.82012)
			(size 0.24994 1.54991)
			(layers "F.Cu" "F.Mask" "F.Paste")
		)
		(pad "B-19" smd rect
			(at -6.20128 -16.77035)
			(size 0.24994 1.54991)
			(layers "F.Cu" "F.Mask" "F.Paste")
			(net "GND")
		)
		(pad "B-20" smd rect
			(at -6.20128 -20.82012)
			(size 0.24994 1.54991)
			(layers "F.Cu" "F.Mask" "F.Paste")
			(net "GND")
		)
		(pad "B-21" smd rect
			(at -5.70141 -16.77035)
			(size 0.24994 1.54991)
			(layers "F.Cu" "F.Mask" "F.Paste")
			(net "ANT1")
		)
		(pad "B-22" smd rect
			(at -5.70141 -20.82012)
			(size 0.24994 1.54991)
			(layers "F.Cu" "F.Mask" "F.Paste")
		)
		(pad "B-23" smd rect
			(at -5.20129 -16.77035)
			(size 0.24994 1.54991)
			(layers "F.Cu" "F.Mask" "F.Paste")
			(net "ANT2")
		)
		(pad "B-24" smd rect
			(at -5.20129 -20.82012)
			(size 0.24994 1.54991)
			(layers "F.Cu" "F.Mask" "F.Paste")
		)
		(pad "B-25" smd rect
			(at -4.70141 -16.77035)
			(size 0.24994 1.54991)
			(layers "F.Cu" "F.Mask" "F.Paste")
			(net "ANT3")
		)
		(pad "B-26" smd rect
			(at -4.70141 -20.82012)
			(size 0.24994 1.54991)
			(layers "F.Cu" "F.Mask" "F.Paste")
			(net "MAC_TX")
		)
		(pad "B-27" smd rect
			(at -4.20129 -16.77035)
			(size 0.24994 1.54991)
			(layers "F.Cu" "F.Mask" "F.Paste")
			(net "ANT4")
		)
		(pad "B-28" smd rect
			(at -4.20129 -20.82012)
			(size 0.24994 1.54991)
			(layers "F.Cu" "F.Mask" "F.Paste")
			(net "MAC_RX")
		)
		(pad "B-29" smd rect
			(at -3.70142 -16.77035)
			(size 0.24994 1.54991)
			(layers "F.Cu" "F.Mask" "F.Paste")
			(net "GND")
		)
		(pad "B-30" smd rect
			(at -3.70142 -20.82012)
			(size 0.24994 1.54991)
			(layers "F.Cu" "F.Mask" "F.Paste")
			(net "GND")
		)
		(pad "B-31" smd rect
			(at -3.20129 -16.77035)
			(size 0.24994 1.54991)
			(layers "F.Cu" "F.Mask" "F.Paste")
		)
		(pad "B-32" smd rect
			(at -3.20129 -20.82012)
			(size 0.24994 1.54991)
			(layers "F.Cu" "F.Mask" "F.Paste")
		)
		(pad "B-33" smd rect
			(at -2.70142 -16.77035)
			(size 0.24994 1.54991)
			(layers "F.Cu" "F.Mask" "F.Paste")
			(net "MAC_10Mout")
		)
		(pad "B-34" smd rect
			(at -2.70142 -20.82012)
			(size 0.24994 1.54991)
			(layers "F.Cu" "F.Mask" "F.Paste")
			(net "DCXO1")
		)
		(pad "B-35" smd rect
			(at -2.20129 -16.77035)
			(size 0.24994 1.54991)
			(layers "F.Cu" "F.Mask" "F.Paste")
			(net "MAC_ALARM")
		)
		(pad "B-36" smd rect
			(at -2.20129 -20.82012)
			(size 0.24994 1.54991)
			(layers "F.Cu" "F.Mask" "F.Paste")
		)
		(pad "B-37" smd rect
			(at -1.70142 -16.77035)
			(size 0.24994 1.54991)
			(layers "F.Cu" "F.Mask" "F.Paste")
			(net "MAC_BITE")
		)
		(pad "B-38" smd rect
			(at -1.70142 -20.82012)
			(size 0.24994 1.54991)
			(layers "F.Cu" "F.Mask" "F.Paste")
		)
		(pad "B-39" smd rect
			(at -1.20129 -16.77035)
			(size 0.24994 1.54991)
			(layers "F.Cu" "F.Mask" "F.Paste")
			(net "GND")
		)
		(pad "B-40" smd rect
			(at -1.20129 -20.82012)
			(size 0.24994 1.54991)
			(layers "F.Cu" "F.Mask" "F.Paste")
			(net "GND")
		)
		(pad "B-41" smd rect
			(at -0.70142 -16.77035)
			(size 0.24994 1.54991)
			(layers "F.Cu" "F.Mask" "F.Paste")
			(net "MAC_PPS_OUT+")
		)
		(pad "B-42" smd rect
			(at -0.70142 -20.82012)
			(size 0.24994 1.54991)
			(layers "F.Cu" "F.Mask" "F.Paste")
		)
		(pad "B-43" smd rect
			(at -0.2013 -16.77035)
			(size 0.24994 1.54991)
			(layers "F.Cu" "F.Mask" "F.Paste")
			(net "MAC_PPS_OUT-")
		)
		(pad "B-44" smd rect
			(at -0.2013 -20.82012)
			(size 0.24994 1.54991)
			(layers "F.Cu" "F.Mask" "F.Paste")
		)
		(pad "B-45" smd rect
			(at 0.29858 -16.77035)
			(size 0.24994 1.54991)
			(layers "F.Cu" "F.Mask" "F.Paste")
			(net "MAC_PPS_IN0+")
		)
		(pad "B-46" smd rect
			(at 0.29858 -20.82012)
			(size 0.24994 1.54991)
			(layers "F.Cu" "F.Mask" "F.Paste")
		)
	)
)
